(kicad_pcb
	(version 20260206)
	(generator "pcbnew")
	(generator_version "10.0")
	(general
		(thickness 1.6)
		(legacy_teardrops no)
	)
	(paper "A4")
	(title_block
		(title "01162023_DA0F0TEBIF0_F0T_Expander_BD_F_brd_V02_OCP.brd")
		(comment 1 "Grand Teton / footprint 5622 of 9728 (PEX2), pads 1424-1536 of 2397")
	)
	(layers
		(0 "F.Cu" signal "TOP")
		(4 "In1.Cu" signal "GND")
		(6 "In2.Cu" signal "VCC")
		(8 "In3.Cu" signal "VCC1")
		(10 "In4.Cu" signal "GND1")
		(12 "In5.Cu" signal "IN1")
		(14 "In6.Cu" signal "GND2")
		(16 "In7.Cu" signal "IN2")
		(18 "In8.Cu" signal "GND3")
		(20 "In9.Cu" signal "IN3")
		(22 "In10.Cu" signal "GND4")
		(24 "In11.Cu" signal "IN4")
		(26 "In12.Cu" signal "GND5")
		(28 "In13.Cu" signal "IN5")
		(30 "In14.Cu" signal "GND6")
		(32 "In15.Cu" signal "IN6")
		(34 "In16.Cu" signal "GND7")
		(2 "B.Cu" signal "BOTTOM")
		(9 "F.Adhes" user "F.Adhesive")
		(11 "B.Adhes" user "B.Adhesive")
		(13 "F.Paste" user "Package Geometry/Pastemask Top")
		(15 "B.Paste" user "Package Geometry/Pastemask Bottom")
		(5 "F.SilkS" user "Ref Des/Silkscreen Top")
		(7 "B.SilkS" user "Ref Des/Silkscreen Bottom")
		(1 "F.Mask" user "Board Geometry/Soldermask Top")
		(3 "B.Mask" user "Board Geometry/Soldermask Bottom")
		(17 "Dwgs.User" user "User.Drawings")
		(19 "Cmts.User" user "User.Comments")
		(21 "Eco1.User" user "User.Eco1")
		(23 "Eco2.User" user "User.Eco2")
		(25 "Edge.Cuts" user "Board Geometry/Outline")
		(27 "Margin" user)
		(31 "F.CrtYd" user "Package Geometry/Place Bound Top")
		(29 "B.CrtYd" user "Package Geometry/Place Bound Bottom")
		(35 "F.Fab" user "Ref Des/Assembly Top")
		(33 "B.Fab" user "Ref Des/Assembly Bottom")
	)
	(footprint ""
		(layer "F.Cu")
		(at 291.84981 -295.89984)
		(property "Reference" "PEX2"
			(at -3.35153 35.56762 0)
			(unlocked yes)
			(layer "F.SilkS")
			(effects
				(font
					(size 2.032 1.524)
					(thickness 0.1524)
				)
				(justify left)
			)
		)
		(property "Value" ""
			(at 0 0 0)
			(layer "F.Fab")
			(effects
				(font
					(size 1.27 1.27)
				)
			)
		)
		(duplicate_pad_numbers_are_jumpers no)
		(pad "BH5" smd circle
			(at -18.999962 21.850096)
			(size 0.4572 0.4572)
			(layers "F.Cu" "F.Mask" "F.Paste")
			(net "Net_1637")
		)
		(pad "BH6" smd circle
			(at -18.050002 21.850096)
			(size 0.4572 0.4572)
			(layers "F.Cu" "F.Mask" "F.Paste")
			(net "GND")
		)
		(pad "BH7" smd circle
			(at -17.100042 21.850096)
			(size 0.4572 0.4572)
			(layers "F.Cu" "F.Mask" "F.Paste")
			(net "Net_1611")
		)
		(pad "BH8" smd circle
			(at -16.150082 21.850096)
			(size 0.4572 0.4572)
			(layers "F.Cu" "F.Mask" "F.Paste")
			(net "GND")
		)
		(pad "BH9" smd circle
			(at -15.200122 21.850096)
			(size 0.4572 0.4572)
			(layers "F.Cu" "F.Mask" "F.Paste")
			(net "P5E_PEX2_STN2_RX_DP<47>")
		)
		(pad "BH10" smd circle
			(at -14.249908 21.850096)
			(size 0.4572 0.4572)
			(layers "F.Cu" "F.Mask" "F.Paste")
			(net "GND")
		)
		(pad "BH11" smd circle
			(at -13.299948 21.850096)
			(size 0.4572 0.4572)
			(layers "F.Cu" "F.Mask" "F.Paste")
			(net "P5E_PEX2_STN2_RX_DP<45>")
		)
		(pad "BH12" smd circle
			(at -12.349988 21.850096)
			(size 0.4572 0.4572)
			(layers "F.Cu" "F.Mask" "F.Paste")
			(net "GND")
		)
		(pad "BH13" smd circle
			(at -11.400028 21.850096)
			(size 0.4572 0.4572)
			(layers "F.Cu" "F.Mask" "F.Paste")
			(net "P5E_PEX2_STN2_RX_DP<43>")
		)
		(pad "BH14" smd circle
			(at -10.450068 21.850096)
			(size 0.4572 0.4572)
			(layers "F.Cu" "F.Mask" "F.Paste")
			(net "GND")
		)
		(pad "BH15" smd circle
			(at -9.500108 21.850096)
			(size 0.4572 0.4572)
			(layers "F.Cu" "F.Mask" "F.Paste")
			(net "P5E_PEX2_STN2_RX_DP<41>")
		)
		(pad "BH16" smd circle
			(at -8.549894 21.850096)
			(size 0.4572 0.4572)
			(layers "F.Cu" "F.Mask" "F.Paste")
			(net "GND")
		)
		(pad "BH17" smd circle
			(at -7.599934 21.850096)
			(size 0.4572 0.4572)
			(layers "F.Cu" "F.Mask" "F.Paste")
			(net "P5E_PEX2_STN2_RX_DP<39>")
		)
		(pad "BH18" smd circle
			(at -6.649974 21.850096)
			(size 0.4572 0.4572)
			(layers "F.Cu" "F.Mask" "F.Paste")
			(net "GND")
		)
		(pad "BH19" smd circle
			(at -5.700014 21.850096)
			(size 0.4572 0.4572)
			(layers "F.Cu" "F.Mask" "F.Paste")
			(net "P5E_PEX2_STN2_RX_DP<37>")
		)
		(pad "BH20" smd circle
			(at -4.750054 21.850096)
			(size 0.4572 0.4572)
			(layers "F.Cu" "F.Mask" "F.Paste")
			(net "GND")
		)
		(pad "BH21" smd circle
			(at -3.800094 21.850096)
			(size 0.4572 0.4572)
			(layers "F.Cu" "F.Mask" "F.Paste")
			(net "P5E_PEX2_STN2_RX_DP<35>")
		)
		(pad "BH22" smd circle
			(at -2.84988 21.850096)
			(size 0.4572 0.4572)
			(layers "F.Cu" "F.Mask" "F.Paste")
			(net "GND")
		)
		(pad "BH23" smd circle
			(at -1.89992 21.850096)
			(size 0.4572 0.4572)
			(layers "F.Cu" "F.Mask" "F.Paste")
			(net "P5E_PEX2_STN2_RX_DP<33>")
		)
		(pad "BH24" smd circle
			(at -0.94996 21.850096)
			(size 0.4572 0.4572)
			(layers "F.Cu" "F.Mask" "F.Paste")
			(net "GND")
		)
		(pad "BH25" smd circle
			(at 0 21.850096)
			(size 0.4572 0.4572)
			(layers "F.Cu" "F.Mask" "F.Paste")
			(net "P5E_PEX2_STN1_RX_DP<16>")
		)
		(pad "BH26" smd circle
			(at 0.94996 21.850096)
			(size 0.4572 0.4572)
			(layers "F.Cu" "F.Mask" "F.Paste")
			(net "GND")
		)
		(pad "BH27" smd circle
			(at 1.89992 21.850096)
			(size 0.4572 0.4572)
			(layers "F.Cu" "F.Mask" "F.Paste")
			(net "P5E_PEX2_STN1_RX_DP<18>")
		)
		(pad "BH28" smd circle
			(at 2.84988 21.850096)
			(size 0.4572 0.4572)
			(layers "F.Cu" "F.Mask" "F.Paste")
			(net "GND")
		)
		(pad "BH29" smd circle
			(at 3.800094 21.850096)
			(size 0.4572 0.4572)
			(layers "F.Cu" "F.Mask" "F.Paste")
			(net "P5E_PEX2_STN1_RX_DP<20>")
		)
		(pad "BH30" smd circle
			(at 4.750054 21.850096)
			(size 0.4572 0.4572)
			(layers "F.Cu" "F.Mask" "F.Paste")
			(net "GND")
		)
		(pad "BH31" smd circle
			(at 5.700014 21.850096)
			(size 0.4572 0.4572)
			(layers "F.Cu" "F.Mask" "F.Paste")
			(net "P5E_PEX2_STN1_RX_DP<22>")
		)
		(pad "BH32" smd circle
			(at 6.649974 21.850096)
			(size 0.4572 0.4572)
			(layers "F.Cu" "F.Mask" "F.Paste")
			(net "GND")
		)
		(pad "BH33" smd circle
			(at 7.599934 21.850096)
			(size 0.4572 0.4572)
			(layers "F.Cu" "F.Mask" "F.Paste")
			(net "P5E_PEX2_STN1_RX_DP<24>")
		)
		(pad "BH34" smd circle
			(at 8.549894 21.850096)
			(size 0.4572 0.4572)
			(layers "F.Cu" "F.Mask" "F.Paste")
			(net "GND")
		)
		(pad "BH35" smd circle
			(at 9.500108 21.850096)
			(size 0.4572 0.4572)
			(layers "F.Cu" "F.Mask" "F.Paste")
			(net "P5E_PEX2_STN1_RX_DP<26>")
		)
		(pad "BH36" smd circle
			(at 10.450068 21.850096)
			(size 0.4572 0.4572)
			(layers "F.Cu" "F.Mask" "F.Paste")
			(net "GND")
		)
		(pad "BH37" smd circle
			(at 11.400028 21.850096)
			(size 0.4572 0.4572)
			(layers "F.Cu" "F.Mask" "F.Paste")
			(net "P5E_PEX2_STN1_RX_DP<28>")
		)
		(pad "BH38" smd circle
			(at 12.349988 21.850096)
			(size 0.4572 0.4572)
			(layers "F.Cu" "F.Mask" "F.Paste")
			(net "GND")
		)
		(pad "BH39" smd circle
			(at 13.299948 21.850096)
			(size 0.4572 0.4572)
			(layers "F.Cu" "F.Mask" "F.Paste")
			(net "P5E_PEX2_STN1_RX_DP<30>")
		)
		(pad "BH40" smd circle
			(at 14.249908 21.850096)
			(size 0.4572 0.4572)
			(layers "F.Cu" "F.Mask" "F.Paste")
			(net "GND")
		)
		(pad "BH41" smd circle
			(at 15.200122 21.850096)
			(size 0.4572 0.4572)
			(layers "F.Cu" "F.Mask" "F.Paste")
			(net "P5E_PEX2_STN0_RX_DP<15>")
		)
		(pad "BH42" smd circle
			(at 16.150082 21.850096)
			(size 0.4572 0.4572)
			(layers "F.Cu" "F.Mask" "F.Paste")
			(net "GND")
		)
		(pad "BH43" smd circle
			(at 17.100042 21.850096)
			(size 0.4572 0.4572)
			(layers "F.Cu" "F.Mask" "F.Paste")
			(net "P5E_PEX2_STN0_RX_DP<13>")
		)
		(pad "BH44" smd circle
			(at 18.050002 21.850096)
			(size 0.4572 0.4572)
			(layers "F.Cu" "F.Mask" "F.Paste")
			(net "GND")
		)
		(pad "BH45" smd circle
			(at 18.999962 21.850096)
			(size 0.4572 0.4572)
			(layers "F.Cu" "F.Mask" "F.Paste")
			(net "P5E_PEX2_STN0_RX_DP<11>")
		)
		(pad "BH46" smd circle
			(at 19.949922 21.850096)
			(size 0.4572 0.4572)
			(layers "F.Cu" "F.Mask" "F.Paste")
			(net "GND")
		)
		(pad "BH47" smd circle
			(at 20.899882 21.850096)
			(size 0.4572 0.4572)
			(layers "F.Cu" "F.Mask" "F.Paste")
			(net "P5E_PEX2_STN0_RX_DP<9>")
		)
		(pad "BH48" smd circle
			(at 21.850096 21.850096)
			(size 0.4572 0.4572)
			(layers "F.Cu" "F.Mask" "F.Paste")
			(net "GND")
		)
		(pad "BH49" smd circle
			(at 22.800056 21.850096)
			(size 0.4572 0.4572)
			(layers "F.Cu" "F.Mask" "F.Paste")
			(net "GND")
		)
		(pad "BJ2" smd circle
			(at -21.850096 22.800056)
			(size 0.4572 0.4572)
			(layers "F.Cu" "F.Mask" "F.Paste")
			(net "GND")
		)
		(pad "BJ3" smd circle
			(at -20.899882 22.800056)
			(size 0.4572 0.4572)
			(layers "F.Cu" "F.Mask" "F.Paste")
			(net "Net_1536")
		)
		(pad "BJ4" smd circle
			(at -19.949922 22.800056)
			(size 0.4572 0.4572)
			(layers "F.Cu" "F.Mask" "F.Paste")
			(net "GND")
		)
		(pad "BJ5" smd circle
			(at -18.999962 22.800056)
			(size 0.4572 0.4572)
			(layers "F.Cu" "F.Mask" "F.Paste")
			(net "Net_1539")
		)
		(pad "BJ6" smd circle
			(at -18.050002 22.800056)
			(size 0.4572 0.4572)
			(layers "F.Cu" "F.Mask" "F.Paste")
			(net "GND")
		)
		(pad "BJ7" smd circle
			(at -17.100042 22.800056)
			(size 0.4572 0.4572)
			(layers "F.Cu" "F.Mask" "F.Paste")
			(net "Net_1534")
		)
		(pad "BJ8" smd circle
			(at -16.150082 22.800056)
			(size 0.4572 0.4572)
			(layers "F.Cu" "F.Mask" "F.Paste")
			(net "GND")
		)
		(pad "BJ9" smd circle
			(at -15.200122 22.800056)
			(size 0.4572 0.4572)
			(layers "F.Cu" "F.Mask" "F.Paste")
			(net "P5E_PEX2_STN2_RX_DN<47>")
		)
		(pad "BJ10" smd circle
			(at -14.249908 22.800056)
			(size 0.4572 0.4572)
			(layers "F.Cu" "F.Mask" "F.Paste")
			(net "GND")
		)
		(pad "BJ11" smd circle
			(at -13.299948 22.800056)
			(size 0.4572 0.4572)
			(layers "F.Cu" "F.Mask" "F.Paste")
			(net "P5E_PEX2_STN2_RX_DN<45>")
		)
		(pad "BJ12" smd circle
			(at -12.349988 22.800056)
			(size 0.4572 0.4572)
			(layers "F.Cu" "F.Mask" "F.Paste")
			(net "GND")
		)
		(pad "BJ13" smd circle
			(at -11.400028 22.800056)
			(size 0.4572 0.4572)
			(layers "F.Cu" "F.Mask" "F.Paste")
			(net "P5E_PEX2_STN2_RX_DN<43>")
		)
		(pad "BJ14" smd circle
			(at -10.450068 22.800056)
			(size 0.4572 0.4572)
			(layers "F.Cu" "F.Mask" "F.Paste")
			(net "GND")
		)
		(pad "BJ15" smd circle
			(at -9.500108 22.800056)
			(size 0.4572 0.4572)
			(layers "F.Cu" "F.Mask" "F.Paste")
			(net "P5E_PEX2_STN2_RX_DN<41>")
		)
		(pad "BJ16" smd circle
			(at -8.549894 22.800056)
			(size 0.4572 0.4572)
			(layers "F.Cu" "F.Mask" "F.Paste")
			(net "GND")
		)
		(pad "BJ17" smd circle
			(at -7.599934 22.800056)
			(size 0.4572 0.4572)
			(layers "F.Cu" "F.Mask" "F.Paste")
			(net "P5E_PEX2_STN2_RX_DN<39>")
		)
		(pad "BJ18" smd circle
			(at -6.649974 22.800056)
			(size 0.4572 0.4572)
			(layers "F.Cu" "F.Mask" "F.Paste")
			(net "GND")
		)
		(pad "BJ19" smd circle
			(at -5.700014 22.800056)
			(size 0.4572 0.4572)
			(layers "F.Cu" "F.Mask" "F.Paste")
			(net "P5E_PEX2_STN2_RX_DN<37>")
		)
		(pad "BJ20" smd circle
			(at -4.750054 22.800056)
			(size 0.4572 0.4572)
			(layers "F.Cu" "F.Mask" "F.Paste")
			(net "GND")
		)
		(pad "BJ21" smd circle
			(at -3.800094 22.800056)
			(size 0.4572 0.4572)
			(layers "F.Cu" "F.Mask" "F.Paste")
			(net "P5E_PEX2_STN2_RX_DN<35>")
		)
		(pad "BJ22" smd circle
			(at -2.84988 22.800056)
			(size 0.4572 0.4572)
			(layers "F.Cu" "F.Mask" "F.Paste")
			(net "GND")
		)
		(pad "BJ23" smd circle
			(at -1.89992 22.800056)
			(size 0.4572 0.4572)
			(layers "F.Cu" "F.Mask" "F.Paste")
			(net "P5E_PEX2_STN2_RX_DN<33>")
		)
		(pad "BJ24" smd circle
			(at -0.94996 22.800056)
			(size 0.4572 0.4572)
			(layers "F.Cu" "F.Mask" "F.Paste")
			(net "GND")
		)
		(pad "BJ25" smd circle
			(at 0 22.800056)
			(size 0.4572 0.4572)
			(layers "F.Cu" "F.Mask" "F.Paste")
			(net "P5E_PEX2_STN1_RX_DN<16>")
		)
		(pad "BJ26" smd circle
			(at 0.94996 22.800056)
			(size 0.4572 0.4572)
			(layers "F.Cu" "F.Mask" "F.Paste")
			(net "GND")
		)
		(pad "BJ27" smd circle
			(at 1.89992 22.800056)
			(size 0.4572 0.4572)
			(layers "F.Cu" "F.Mask" "F.Paste")
			(net "P5E_PEX2_STN1_RX_DN<18>")
		)
		(pad "BJ28" smd circle
			(at 2.84988 22.800056)
			(size 0.4572 0.4572)
			(layers "F.Cu" "F.Mask" "F.Paste")
			(net "GND")
		)
		(pad "BJ29" smd circle
			(at 3.800094 22.800056)
			(size 0.4572 0.4572)
			(layers "F.Cu" "F.Mask" "F.Paste")
			(net "P5E_PEX2_STN1_RX_DN<20>")
		)
		(pad "BJ30" smd circle
			(at 4.750054 22.800056)
			(size 0.4572 0.4572)
			(layers "F.Cu" "F.Mask" "F.Paste")
			(net "GND")
		)
		(pad "BJ31" smd circle
			(at 5.700014 22.800056)
			(size 0.4572 0.4572)
			(layers "F.Cu" "F.Mask" "F.Paste")
			(net "P5E_PEX2_STN1_RX_DN<22>")
		)
		(pad "BJ32" smd circle
			(at 6.649974 22.800056)
			(size 0.4572 0.4572)
			(layers "F.Cu" "F.Mask" "F.Paste")
			(net "GND")
		)
		(pad "BJ33" smd circle
			(at 7.599934 22.800056)
			(size 0.4572 0.4572)
			(layers "F.Cu" "F.Mask" "F.Paste")
			(net "P5E_PEX2_STN1_RX_DN<24>")
		)
		(pad "BJ34" smd circle
			(at 8.549894 22.800056)
			(size 0.4572 0.4572)
			(layers "F.Cu" "F.Mask" "F.Paste")
			(net "GND")
		)
		(pad "BJ35" smd circle
			(at 9.500108 22.800056)
			(size 0.4572 0.4572)
			(layers "F.Cu" "F.Mask" "F.Paste")
			(net "P5E_PEX2_STN1_RX_DN<26>")
		)
		(pad "BJ36" smd circle
			(at 10.450068 22.800056)
			(size 0.4572 0.4572)
			(layers "F.Cu" "F.Mask" "F.Paste")
			(net "GND")
		)
		(pad "BJ37" smd circle
			(at 11.400028 22.800056)
			(size 0.4572 0.4572)
			(layers "F.Cu" "F.Mask" "F.Paste")
			(net "P5E_PEX2_STN1_RX_DN<28>")
		)
		(pad "BJ38" smd circle
			(at 12.349988 22.800056)
			(size 0.4572 0.4572)
			(layers "F.Cu" "F.Mask" "F.Paste")
			(net "GND")
		)
		(pad "BJ39" smd circle
			(at 13.299948 22.800056)
			(size 0.4572 0.4572)
			(layers "F.Cu" "F.Mask" "F.Paste")
			(net "P5E_PEX2_STN1_RX_DN<30>")
		)
		(pad "BJ40" smd circle
			(at 14.249908 22.800056)
			(size 0.4572 0.4572)
			(layers "F.Cu" "F.Mask" "F.Paste")
			(net "GND")
		)
		(pad "BJ41" smd circle
			(at 15.200122 22.800056)
			(size 0.4572 0.4572)
			(layers "F.Cu" "F.Mask" "F.Paste")
			(net "P5E_PEX2_STN0_RX_DN<15>")
		)
		(pad "BJ42" smd circle
			(at 16.150082 22.800056)
			(size 0.4572 0.4572)
			(layers "F.Cu" "F.Mask" "F.Paste")
			(net "GND")
		)
		(pad "BJ43" smd circle
			(at 17.100042 22.800056)
			(size 0.4572 0.4572)
			(layers "F.Cu" "F.Mask" "F.Paste")
			(net "P5E_PEX2_STN0_RX_DN<13>")
		)
		(pad "BJ44" smd circle
			(at 18.050002 22.800056)
			(size 0.4572 0.4572)
			(layers "F.Cu" "F.Mask" "F.Paste")
			(net "GND")
		)
		(pad "BJ45" smd circle
			(at 18.999962 22.800056)
			(size 0.4572 0.4572)
			(layers "F.Cu" "F.Mask" "F.Paste")
			(net "P5E_PEX2_STN0_RX_DN<11>")
		)
		(pad "BJ46" smd circle
			(at 19.949922 22.800056)
			(size 0.4572 0.4572)
			(layers "F.Cu" "F.Mask" "F.Paste")
			(net "GND")
		)
		(pad "BJ47" smd circle
			(at 20.899882 22.800056)
			(size 0.4572 0.4572)
			(layers "F.Cu" "F.Mask" "F.Paste")
			(net "P5E_PEX2_STN0_RX_DN<9>")
		)
		(pad "BJ48" smd circle
			(at 21.850096 22.800056)
			(size 0.4572 0.4572)
			(layers "F.Cu" "F.Mask" "F.Paste")
			(net "GND")
		)
		(pad "C1" smd circle
			(at -22.800056 -20.899882)
			(size 0.4572 0.4572)
			(layers "F.Cu" "F.Mask" "F.Paste")
			(net "P5E_PEX2_STN7_RX_DN<122>")
		)
		(pad "C2" smd circle
			(at -21.850096 -20.899882)
			(size 0.4572 0.4572)
			(layers "F.Cu" "F.Mask" "F.Paste")
			(net "P5E_PEX2_STN7_RX_DP<122>")
		)
		(pad "C3" smd circle
			(at -20.899882 -20.899882)
			(size 0.4572 0.4572)
			(layers "F.Cu" "F.Mask" "F.Paste")
			(net "GND")
		)
		(pad "C4" smd circle
			(at -19.949922 -20.899882)
			(size 0.4572 0.4572)
			(layers "F.Cu" "F.Mask" "F.Paste")
			(net "P5E_PEX2_STN7_RX_DN<124>")
		)
		(pad "C5" smd circle
			(at -18.999962 -20.899882)
			(size 0.4572 0.4572)
			(layers "F.Cu" "F.Mask" "F.Paste")
			(net "GND")
		)
		(pad "C6" smd circle
			(at -18.050002 -20.899882)
			(size 0.4572 0.4572)
			(layers "F.Cu" "F.Mask" "F.Paste")
			(net "P5E_PEX2_STN7_RX_DN<126>")
		)
		(pad "C7" smd circle
			(at -17.100042 -20.899882)
			(size 0.4572 0.4572)
			(layers "F.Cu" "F.Mask" "F.Paste")
			(net "GND")
		)
		(pad "C8" smd circle
			(at -16.150082 -20.899882)
			(size 0.4572 0.4572)
			(layers "F.Cu" "F.Mask" "F.Paste")
			(net "P5E_PEX2_STN6_RX_DN<111>")
		)
		(pad "C9" smd circle
			(at -15.200122 -20.899882)
			(size 0.4572 0.4572)
			(layers "F.Cu" "F.Mask" "F.Paste")
			(net "GND")
		)
		(pad "C10" smd circle
			(at -14.249908 -20.899882)
			(size 0.4572 0.4572)
			(layers "F.Cu" "F.Mask" "F.Paste")
			(net "P5E_PEX2_STN6_RX_DN<109>")
		)
		(pad "C11" smd circle
			(at -13.299948 -20.899882)
			(size 0.4572 0.4572)
			(layers "F.Cu" "F.Mask" "F.Paste")
			(net "GND")
		)
		(pad "C12" smd circle
			(at -12.349988 -20.899882)
			(size 0.4572 0.4572)
			(layers "F.Cu" "F.Mask" "F.Paste")
			(net "P5E_PEX2_STN6_RX_DN<107>")
		)
		(pad "C13" smd circle
			(at -11.400028 -20.899882)
			(size 0.4572 0.4572)
			(layers "F.Cu" "F.Mask" "F.Paste")
			(net "GND")
		)
		(pad "C14" smd circle
			(at -10.450068 -20.899882)
			(size 0.4572 0.4572)
			(layers "F.Cu" "F.Mask" "F.Paste")
			(net "P5E_PEX2_STN6_RX_DN<105>")
		)
		(pad "C15" smd circle
			(at -9.500108 -20.899882)
			(size 0.4572 0.4572)
			(layers "F.Cu" "F.Mask" "F.Paste")
			(net "GND")
		)
		(pad "C16" smd circle
			(at -8.549894 -20.899882)
			(size 0.4572 0.4572)
			(layers "F.Cu" "F.Mask" "F.Paste")
			(net "P5E_PEX2_STN6_RX_DN<103>")
		)
		(pad "C17" smd circle
			(at -7.599934 -20.899882)
			(size 0.4572 0.4572)
			(layers "F.Cu" "F.Mask" "F.Paste")
			(net "GND")
		)
		(pad "C18" smd circle
			(at -6.649974 -20.899882)
			(size 0.4572 0.4572)
			(layers "F.Cu" "F.Mask" "F.Paste")
			(net "P5E_PEX2_STN6_RX_DN<101>")
		)
		(pad "C19" smd circle
			(at -5.700014 -20.899882)
			(size 0.4572 0.4572)
			(layers "F.Cu" "F.Mask" "F.Paste")
			(net "GND")
		)
		(pad "C20" smd circle
			(at -4.750054 -20.899882)
			(size 0.4572 0.4572)
			(layers "F.Cu" "F.Mask" "F.Paste")
			(net "P5E_PEX2_STN6_RX_DN<99>")
		)
		(pad "C21" smd circle
			(at -3.800094 -20.899882)
			(size 0.4572 0.4572)
			(layers "F.Cu" "F.Mask" "F.Paste")
			(net "GND")
		)
	)
)
